# T6G (Grand Teton) — schematic netlist excerpt (pin names and nets, part order shuffled) for the footprints in the layout excerpt that follows; sources: Cadence DE-HDL packaged netlist, KiCad conversion of 04192023_DAF0TMB3IC0_F0TG_MB_C_brd_V02_OCP.brd

PR94  Q_RES  2.2 1% CHIP  pkg 0402LF  page 203 : A = PVDDCR_CPU1_P0_PVCC ; B = PVDDCR_CPU1_P0_VCC5
C520  Q_CAP  0.1UF 10V 10% X7S  pkg C0201  page 279 : A = P1V8_CPU0_RT0_1A ; B = GND
C416  Q_CAP  4.7UF 6.3V 20% X6S  pkg 0402  page 345 : A = P0V9_CPU1_RT2_2A ; B = GND

(kicad_pcb
	(version 20260206)
	(generator "pcbnew")
	(generator_version "10.0")
	(general
		(thickness 1.6)
		(legacy_teardrops no)
	)
	(paper "A4")
	(title_block
		(title "04192023_DAF0TMB3IC0_F0TG_MB_C_brd_V02_OCP.brd")
		(comment 1 "Grand Teton / footprints 7726-7728 of 8354")
	)
	(layers
		(0 "F.Cu" signal "TOP")
		(4 "In1.Cu" signal "GND")
		(6 "In2.Cu" signal "IN1")
		(8 "In3.Cu" signal "GND1")
		(10 "In4.Cu" signal "IN2")
		(12 "In5.Cu" signal "GND2")
		(14 "In6.Cu" signal "IN3")
		(16 "In7.Cu" signal "GND3")
		(18 "In8.Cu" signal "VCC")
		(20 "In9.Cu" signal "VCC1")
		(22 "In10.Cu" signal "GND4")
		(24 "In11.Cu" signal "IN4")
		(26 "In12.Cu" signal "GND5")
		(28 "In13.Cu" signal "IN5")
		(30 "In14.Cu" signal "GND6")
		(32 "In15.Cu" signal "IN6")
		(34 "In16.Cu" signal "GND7")
		(2 "B.Cu" signal "BOTTOM")
		(9 "F.Adhes" user "F.Adhesive")
		(11 "B.Adhes" user "B.Adhesive")
		(13 "F.Paste" user "Package Geometry/Pastemask Top")
		(15 "B.Paste" user "Package Geometry/Pastemask Bottom")
		(5 "F.SilkS" user "Ref Des/Silkscreen Top")
		(7 "B.SilkS" user "Ref Des/Silkscreen Bottom")
		(1 "F.Mask" user "Board Geometry/Soldermask Top")
		(3 "B.Mask" user "Board Geometry/Soldermask Bottom")
		(17 "Dwgs.User" user "User.Drawings")
		(19 "Cmts.User" user "User.Comments")
		(21 "Eco1.User" user "User.Eco1")
		(23 "Eco2.User" user "User.Eco2")
		(25 "Edge.Cuts" user "Board Geometry/Outline")
		(27 "Margin" user)
		(31 "F.CrtYd" user "Package Geometry/Place Bound Top")
		(29 "B.CrtYd" user "Package Geometry/Place Bound Bottom")
		(35 "F.Fab" user "Ref Des/Assembly Top")
		(33 "B.Fab" user "Ref Des/Assembly Bottom")
	)
	(footprint ""
		(layer "B.Cu")
		(at 160.218882 -390.560052 90)
		(property "Reference" "C416"
			(at 0 0 90)
			(layer "B.SilkS")
			(hide yes)
			(effects
				(font
					(size 1.27 1.27)
				)
				(justify mirror)
			)
		)
		(property "Value" ""
			(at 0 0 90)
			(layer "B.Fab")
			(effects
				(font
					(size 1.27 1.27)
				)
				(justify mirror)
			)
		)
		(duplicate_pad_numbers_are_jumpers no)
		(fp_line
			(start 0.7874 -0.4064)
			(end -0.7874 -0.4064)
			(stroke
				(width 0.1524)
				(type default)
			)
			(layer "B.SilkS")
		)
		(fp_line
			(start -0.7874 -0.4064)
			(end -0.7874 0.4064)
			(stroke
				(width 0.1524)
				(type default)
			)
			(layer "B.SilkS")
		)
		(fp_line
			(start 0.7874 0.4064)
			(end 0.7874 -0.4064)
			(stroke
				(width 0.1524)
				(type default)
			)
			(layer "B.SilkS")
		)
		(fp_line
			(start -0.7874 0.4064)
			(end 0.7874 0.4064)
			(stroke
				(width 0.1524)
				(type default)
			)
			(layer "B.SilkS")
		)
		(fp_line
			(start 0.67945 -0.305054)
			(end 0.12065 -0.305054)
			(stroke
				(width 0.1)
				(type default)
			)
			(layer "B.Fab")
		)
		(fp_line
			(start 0.12065 -0.305054)
			(end 0.12065 -0.2794)
			(stroke
				(width 0.1)
				(type default)
			)
			(layer "B.Fab")
		)
		(fp_line
			(start -0.12065 -0.3048)
			(end -0.67945 -0.3048)
			(stroke
				(width 0.1)
				(type default)
			)
			(layer "B.Fab")
		)
		(fp_line
			(start -0.67945 -0.3048)
			(end -0.67945 0.3048)
			(stroke
				(width 0.1)
				(type default)
			)
			(layer "B.Fab")
		)
		(fp_line
			(start 0.12065 -0.2794)
			(end -0.12065 -0.2794)
			(stroke
				(width 0.1)
				(type default)
			)
			(layer "B.Fab")
		)
		(fp_line
			(start -0.12065 -0.2794)
			(end -0.12065 -0.3048)
			(stroke
				(width 0.1)
				(type default)
			)
			(layer "B.Fab")
		)
		(fp_line
			(start 0.12065 0.2794)
			(end 0.12065 0.3048)
			(stroke
				(width 0.1)
				(type default)
			)
			(layer "B.Fab")
		)
		(fp_line
			(start -0.120396 0.2794)
			(end 0.12065 0.2794)
			(stroke
				(width 0.1)
				(type default)
			)
			(layer "B.Fab")
		)
		(fp_line
			(start 0.67945 0.3048)
			(end 0.67945 -0.305054)
			(stroke
				(width 0.1)
				(type default)
			)
			(layer "B.Fab")
		)
		(fp_line
			(start 0.12065 0.3048)
			(end 0.67945 0.3048)
			(stroke
				(width 0.1)
				(type default)
			)
			(layer "B.Fab")
		)
		(fp_line
			(start -0.120396 0.3048)
			(end -0.120396 0.2794)
			(stroke
				(width 0.1)
				(type default)
			)
			(layer "B.Fab")
		)
		(fp_line
			(start -0.67945 0.3048)
			(end -0.120396 0.3048)
			(stroke
				(width 0.1)
				(type default)
			)
			(layer "B.Fab")
		)
		(pad "1" smd circle
			(at 0.40005 0 270)
			(size 0 0)
			(layers "B.Cu" "B.Mask" "B.Paste")
			(net "P0V9_CPU1_RT2_2A")
		)
		(pad "2" smd circle
			(at -0.40005 0 270)
			(size 0 0)
			(layers "B.Cu" "B.Mask" "B.Paste")
			(net "GND")
		)
	)
	(footprint ""
		(layer "B.Cu")
		(at 341.079328 -336.083656 -90)
		(property "Reference" "PR94"
			(at 0 0 90)
			(layer "B.SilkS")
			(hide yes)
			(effects
				(font
					(size 1.27 1.27)
				)
				(justify mirror)
			)
		)
		(property "Value" ""
			(at 0 0 90)
			(layer "B.Fab")
			(effects
				(font
					(size 1.27 1.27)
				)
				(justify mirror)
			)
		)
		(duplicate_pad_numbers_are_jumpers no)
		(fp_line
			(start -0.7874 0.4064)
			(end 0.7874 0.4064)
			(stroke
				(width 0.1524)
				(type default)
			)
			(layer "B.SilkS")
		)
		(fp_line
			(start 0.7874 0.4064)
			(end 0.7874 -0.4064)
			(stroke
				(width 0.1524)
				(type default)
			)
			(layer "B.SilkS")
		)
		(fp_line
			(start -0.7874 -0.4064)
			(end -0.7874 0.4064)
			(stroke
				(width 0.1524)
				(type default)
			)
			(layer "B.SilkS")
		)
		(fp_line
			(start 0.7874 -0.4064)
			(end -0.7874 -0.4064)
			(stroke
				(width 0.1524)
				(type default)
			)
			(layer "B.SilkS")
		)
		(fp_line
			(start -0.67945 0.3048)
			(end -0.120396 0.3048)
			(stroke
				(width 0.1)
				(type default)
			)
			(layer "B.Fab")
		)
		(fp_line
			(start -0.120396 0.3048)
			(end -0.120396 0.2794)
			(stroke
				(width 0.1)
				(type default)
			)
			(layer "B.Fab")
		)
		(fp_line
			(start 0.12065 0.3048)
			(end 0.67945 0.3048)
			(stroke
				(width 0.1)
				(type default)
			)
			(layer "B.Fab")
		)
		(fp_line
			(start 0.67945 0.3048)
			(end 0.67945 -0.305054)
			(stroke
				(width 0.1)
				(type default)
			)
			(layer "B.Fab")
		)
		(fp_line
			(start -0.120396 0.2794)
			(end 0.12065 0.2794)
			(stroke
				(width 0.1)
				(type default)
			)
			(layer "B.Fab")
		)
		(fp_line
			(start 0.12065 0.2794)
			(end 0.12065 0.3048)
			(stroke
				(width 0.1)
				(type default)
			)
			(layer "B.Fab")
		)
		(fp_line
			(start -0.12065 -0.2794)
			(end -0.12065 -0.3048)
			(stroke
				(width 0.1)
				(type default)
			)
			(layer "B.Fab")
		)
		(fp_line
			(start 0.12065 -0.2794)
			(end -0.12065 -0.2794)
			(stroke
				(width 0.1)
				(type default)
			)
			(layer "B.Fab")
		)
		(fp_line
			(start -0.67945 -0.3048)
			(end -0.67945 0.3048)
			(stroke
				(width 0.1)
				(type default)
			)
			(layer "B.Fab")
		)
		(fp_line
			(start -0.12065 -0.3048)
			(end -0.67945 -0.3048)
			(stroke
				(width 0.1)
				(type default)
			)
			(layer "B.Fab")
		)
		(fp_line
			(start 0.12065 -0.305054)
			(end 0.12065 -0.2794)
			(stroke
				(width 0.1)
				(type default)
			)
			(layer "B.Fab")
		)
		(fp_line
			(start 0.67945 -0.305054)
			(end 0.12065 -0.305054)
			(stroke
				(width 0.1)
				(type default)
			)
			(layer "B.Fab")
		)
		(pad "1" smd circle
			(at 0.40005 0 90)
			(size 0 0)
			(layers "B.Cu" "B.Mask" "B.Paste")
			(net "PVDDCR_CPU1_P0_PVCC")
		)
		(pad "2" smd circle
			(at -0.40005 0 90)
			(size 0 0)
			(layers "B.Cu" "B.Mask" "B.Paste")
			(net "PVDDCR_CPU1_P0_VCC5")
		)
	)
	(footprint ""
		(layer "B.Cu")
		(at 310.578246 -395.148562 90)
		(property "Reference" "C520"
			(at 0 0 90)
			(layer "B.SilkS")
			(hide yes)
			(effects
				(font
					(size 1.27 1.27)
				)
				(justify mirror)
			)
		)
		(property "Value" ""
			(at 0 0 90)
			(layer "B.Fab")
			(effects
				(font
					(size 1.27 1.27)
				)
				(justify mirror)
			)
		)
		(duplicate_pad_numbers_are_jumpers no)
		(fp_line
			(start 0.299974 -0.150114)
			(end -0.299974 -0.150114)
			(stroke
				(width 0.1)
				(type default)
			)
			(layer "B.Fab")
		)
		(fp_line
			(start -0.299974 -0.150114)
			(end -0.299974 0.150114)
			(stroke
				(width 0.1)
				(type default)
			)
			(layer "B.Fab")
		)
		(fp_line
			(start 0.299974 0.150114)
			(end 0.299974 -0.150114)
			(stroke
				(width 0.1)
				(type default)
			)
			(layer "B.Fab")
		)
		(fp_line
			(start -0.299974 0.150114)
			(end 0.299974 0.150114)
			(stroke
				(width 0.1)
				(type default)
			)
			(layer "B.Fab")
		)
		(pad "1" smd rect
			(at 0.2667 0 270)
			(size 0.3048 0.381)
			(layers "B.Cu" "B.Mask" "B.Paste")
			(net "P1V8_CPU0_RT0_1A")
		)
		(pad "2" smd rect
			(at -0.2667 0 270)
			(size 0.3048 0.381)
			(layers "B.Cu" "B.Mask" "B.Paste")
			(net "GND")
		)
	)
)
